(kicad_pcb
	(version 20260206)
	(generator "pcbnew")
	(generator_version "10.0")
	(general
		(thickness 1.6)
		(legacy_teardrops no)
	)
	(paper "A4")
	(title_block
		(title "timecard-production-celestica-r4006 — R4006-B0001-02_R01.brd")
		(comment 1 "Time Appliance Project (Time Card) / footprints 254-258 of 1113")
	)
	(layers
		(0 "F.Cu" signal "TOP")
		(4 "In1.Cu" signal "L02_GND1")
		(6 "In2.Cu" signal "L03_SIG1")
		(8 "In3.Cu" signal "L04_GND2")
		(10 "In4.Cu" signal "L05_VCC1")
		(12 "In5.Cu" signal "L06_VCC2")
		(14 "In6.Cu" signal "L07_GND3")
		(16 "In7.Cu" signal "L08_SIG2")
		(18 "In8.Cu" signal "L09_GND4")
		(2 "B.Cu" signal "BOTTOM")
		(9 "F.Adhes" user "F.Adhesive")
		(11 "B.Adhes" user "B.Adhesive")
		(13 "F.Paste" user "Package Geometry/Pastemask Top")
		(15 "B.Paste" user "Package Geometry/Pastemask Bottom")
		(5 "F.SilkS" user "Ref Des/Silkscreen Top")
		(7 "B.SilkS" user "Ref Des/Silkscreen Bottom")
		(1 "F.Mask" user "Board Geometry/Soldermask Top")
		(3 "B.Mask" user "Board Geometry/Soldermask Bottom")
		(17 "Dwgs.User" user "User.Drawings")
		(19 "Cmts.User" user "User.Comments")
		(21 "Eco1.User" user "User.Eco1")
		(23 "Eco2.User" user "User.Eco2")
		(25 "Edge.Cuts" user "Board Geometry/Outline")
		(27 "Margin" user)
		(31 "F.CrtYd" user "Package Geometry/Place Bound Top")
		(29 "B.CrtYd" user "Package Geometry/Place Bound Bottom")
		(35 "F.Fab" user "Ref Des/Assembly Top")
		(33 "B.Fab" user "Ref Des/Assembly Bottom")
	)
	(footprint ""
		(layer "F.Cu")
		(at 33.7693 -16.7132 180)
		(property "Reference" "R312"
			(at -2.6543 -2.07137 0)
			(unlocked yes)
			(layer "F.SilkS")
			(effects
				(font
					(size 0.7874 0.5842)
					(thickness 0.1524)
				)
			)
		)
		(property "Value" "VAL*"
			(at 0.02032 2.13233 180)
			(unlocked yes)
			(layer "F.Fab")
			(hide yes)
			(effects
				(font
					(size 0.7874 0.5842)
					(thickness 0.1524)
				)
			)
		)
		(property "Device Type" "RESISTOR-G155-100R0-J0,0OHM,-"
			(at 0.008382 1.210564 180)
			(unlocked yes)
			(layer "F.Fab")
			(hide yes)
			(effects
				(font
					(size 0.7874 0.5842)
					(thickness 0.1524)
				)
			)
		)
		(property "User Part Number" "PARTNUM*"
			(at 0.02032 4.024884 180)
			(unlocked yes)
			(layer "Cmts.User")
			(hide yes)
			(effects
				(font
					(size 0.7874 0.5842)
					(thickness 0.1524)
				)
			)
		)
		(property "Tolerance" "TOL*"
			(at 0.044704 3.05435 180)
			(unlocked yes)
			(layer "Cmts.User")
			(hide yes)
			(effects
				(font
					(size 0.7874 0.5842)
					(thickness 0.1524)
				)
			)
		)
		(duplicate_pad_numbers_are_jumpers no)
		(fp_line
			(start 1.143 0.5588)
			(end 1.143 -0.5588)
			(stroke
				(width 0.1)
				(type default)
			)
			(layer "F.SilkS")
		)
		(fp_line
			(start 1.143 -0.5588)
			(end -1.143 -0.5588)
			(stroke
				(width 0.1)
				(type default)
			)
			(layer "F.SilkS")
		)
		(fp_line
			(start -1.143 0.5588)
			(end 1.143 0.5588)
			(stroke
				(width 0.1)
				(type default)
			)
			(layer "F.SilkS")
		)
		(fp_line
			(start -1.143 -0.5588)
			(end -1.143 0.5588)
			(stroke
				(width 0.1)
				(type default)
			)
			(layer "F.SilkS")
		)
		(fp_poly
			(pts
				(xy -1.143 0.5588) (xy 1.143 0.5588) (xy 1.143 -0.5588) (xy -1.143 -0.5588)
			)
			(stroke
				(width 0)
				(type default)
			)
			(fill no)
			(layer "F.CrtYd")
		)
		(fp_line
			(start 0.508 0.3048)
			(end 0.508 -0.3048)
			(stroke
				(width 0.1)
				(type default)
			)
			(layer "F.Fab")
		)
		(fp_line
			(start 0.508 -0.3048)
			(end -0.508 -0.3048)
			(stroke
				(width 0.1)
				(type default)
			)
			(layer "F.Fab")
		)
		(fp_line
			(start -0.508 0.3048)
			(end 0.508 0.3048)
			(stroke
				(width 0.1)
				(type default)
			)
			(layer "F.Fab")
		)
		(fp_line
			(start -0.508 -0.3048)
			(end -0.508 0.3048)
			(stroke
				(width 0.1)
				(type default)
			)
			(layer "F.Fab")
		)
		(pad "1" smd rect
			(at -0.5334 0 180)
			(size 0.7112 0.6096)
			(layers "F.Cu" "F.Mask" "F.Paste")
			(net "RGB_LED_I2C_SDA")
		)
		(pad "2" smd rect
			(at 0.5334 0 180)
			(size 0.7112 0.6096)
			(layers "F.Cu" "F.Mask" "F.Paste")
			(net "EEPROM_SDA")
		)
		(zone
			(layer "F.Cu")
			(hatch none 0.5)
			(connect_pads
				(clearance 0)
			)
			(min_thickness 0.25)
			(keepout
				(tracks allowed)
				(vias not_allowed)
				(pads allowed)
				(copperpour not_allowed)
				(footprints allowed)
			)
			(placement
				(enabled no)
				(sheetname "")
			)
			(fill
				(thermal_gap 0.5)
				(thermal_bridge_width 0.5)
				(island_removal_mode 0)
			)
			(polygon
				(pts
					(xy 33.8455 -17.018) (xy 33.6931 -17.018) (xy 33.6931 -16.4084) (xy 33.8455 -16.4084)
				)
			)
		)
		(zone
			(layer "F.Cu")
			(hatch none 0.5)
			(connect_pads
				(clearance 0)
			)
			(min_thickness 0.25)
			(keepout
				(tracks not_allowed)
				(vias allowed)
				(pads allowed)
				(copperpour not_allowed)
				(footprints allowed)
			)
			(placement
				(enabled no)
				(sheetname "")
			)
			(fill
				(thermal_gap 0.5)
				(thermal_bridge_width 0.5)
				(island_removal_mode 0)
			)
			(polygon
				(pts
					(xy 33.8455 -17.018) (xy 33.6931 -17.018) (xy 33.6931 -16.4084) (xy 33.8455 -16.4084)
				)
			)
		)
	)
	(footprint ""
		(layer "F.Cu")
		(at 86.36 -93.599 90)
		(property "Reference" "C22"
			(at -3.81 -4.78663 90)
			(unlocked yes)
			(layer "F.SilkS")
			(effects
				(font
					(size 0.7874 0.5842)
					(thickness 0.1524)
				)
			)
		)
		(property "Value" "VAL*"
			(at 0.0762 3.134106 90)
			(unlocked yes)
			(layer "F.Fab")
			(hide yes)
			(effects
				(font
					(size 0.7874 0.5842)
					(thickness 0.1524)
				)
			)
		)
		(property "Tolerance" "TOL*"
			(at 0.0762 4.048506 90)
			(unlocked yes)
			(layer "Cmts.User")
			(hide yes)
			(effects
				(font
					(size 0.7874 0.5842)
					(thickness 0.1524)
				)
			)
		)
		(property "User Part Number" "PARTNUM*"
			(at 0.1016 5.013706 90)
			(unlocked yes)
			(layer "Cmts.User")
			(hide yes)
			(effects
				(font
					(size 0.7874 0.5842)
					(thickness 0.1524)
				)
			)
		)
		(property "Device Type" "CAPACITOR-G107-0F226-CM,22UF,2A"
			(at 0.0508 2.194306 90)
			(unlocked yes)
			(layer "F.Fab")
			(hide yes)
			(effects
				(font
					(size 0.7874 0.5842)
					(thickness 0.1524)
				)
			)
		)
		(duplicate_pad_numbers_are_jumpers no)
		(fp_line
			(start 1.5748 -0.9398)
			(end -1.5748 -0.9398)
			(stroke
				(width 0.1)
				(type default)
			)
			(layer "F.SilkS")
		)
		(fp_line
			(start -1.5748 -0.9398)
			(end -1.5748 0.9398)
			(stroke
				(width 0.1)
				(type default)
			)
			(layer "F.SilkS")
		)
		(fp_line
			(start 1.5748 0.9398)
			(end 1.5748 -0.9398)
			(stroke
				(width 0.1)
				(type default)
			)
			(layer "F.SilkS")
		)
		(fp_line
			(start -1.5748 0.9398)
			(end 1.5748 0.9398)
			(stroke
				(width 0.1)
				(type default)
			)
			(layer "F.SilkS")
		)
		(fp_rect
			(start 1.5748 0.9398)
			(end -1.5748 -0.9398)
			(stroke
				(width 0)
				(type default)
			)
			(fill no)
			(layer "F.CrtYd")
		)
		(fp_line
			(start 1.016 -0.635)
			(end -1.016 -0.635)
			(stroke
				(width 0.1)
				(type default)
			)
			(layer "F.Fab")
		)
		(fp_line
			(start -1.016 -0.635)
			(end -1.016 0.635)
			(stroke
				(width 0.1)
				(type default)
			)
			(layer "F.Fab")
		)
		(fp_line
			(start 1.016 0.635)
			(end 1.016 -0.635)
			(stroke
				(width 0.1)
				(type default)
			)
			(layer "F.Fab")
		)
		(fp_line
			(start -1.016 0.635)
			(end 1.016 0.635)
			(stroke
				(width 0.1)
				(type default)
			)
			(layer "F.Fab")
		)
		(pad "1" smd rect
			(at -0.8382 0 90)
			(size 0.9652 1.3716)
			(layers "F.Cu" "F.Mask" "F.Paste")
			(net "XP3R3V")
		)
		(pad "2" smd rect
			(at 0.8382 0 90)
			(size 0.9652 1.3716)
			(layers "F.Cu" "F.Mask" "F.Paste")
			(net "SG")
		)
		(zone
			(layer "F.Cu")
			(hatch none 0.5)
			(connect_pads
				(clearance 0)
			)
			(min_thickness 0.25)
			(keepout
				(tracks allowed)
				(vias not_allowed)
				(pads allowed)
				(copperpour not_allowed)
				(footprints allowed)
			)
			(placement
				(enabled no)
				(sheetname "")
			)
			(fill
				(thermal_gap 0.5)
				(thermal_bridge_width 0.5)
				(island_removal_mode 0)
			)
			(polygon
				(pts
					(xy 86.995 -93.8276) (xy 85.725 -93.8276) (xy 85.725 -93.3704) (xy 86.995 -93.3704)
				)
			)
		)
	)
	(footprint ""
		(layer "F.Cu")
		(at 7.500112 -94.749874)
		(property "Reference" "ME9"
			(at 0.127508 -4.024376 0)
			(unlocked yes)
			(layer "F.SilkS")
			(effects
				(font
					(size 0.7874 0.5842)
					(thickness 0.1524)
				)
			)
		)
		(property "Value" ""
			(at 0 0 0)
			(layer "F.Fab")
			(effects
				(font
					(size 1.27 1.27)
				)
			)
		)
		(property "Device Type" "MEC_MTH8-MTH125C236N_V8-MTH125A"
			(at 0 5.08127 0)
			(unlocked yes)
			(layer "F.Fab")
			(hide yes)
			(effects
				(font
					(size 0.7874 0.5842)
					(thickness 0.1524)
				)
			)
		)
		(duplicate_pad_numbers_are_jumpers no)
		(fp_poly
			(pts
				(arc
					(start 3.5052 0)
					(mid -3.5052 0)
					(end 3.5052 0)
				)
			)
			(stroke
				(width 0)
				(type default)
			)
			(fill no)
			(layer "B.CrtYd")
		)
		(fp_poly
			(pts
				(arc
					(start 3.5052 0)
					(mid -3.5052 0)
					(end 3.5052 0)
				)
			)
			(stroke
				(width 0)
				(type default)
			)
			(fill no)
			(layer "F.CrtYd")
		)
		(fp_circle
			(center 0 0)
			(end 2.9972 0)
			(stroke
				(width 0.1)
				(type default)
			)
			(fill no)
			(layer "B.Fab")
		)
		(fp_circle
			(center 0 0)
			(end 2.9972 0)
			(stroke
				(width 0.1)
				(type default)
			)
			(fill no)
			(layer "F.Fab")
		)
		(pad "" np_thru_hole circle
			(at 0 0)
			(size 2.921 2.921)
			(drill 3.175)
			(layers "*.Cu" "*.Mask")
			(padstack
				(mode front_inner_back)
				(layer "Inner"
					(shape circle)
					(size 2.921 2.921)
					(clearance 0.4445)
				)
				(layer "B.Cu"
					(shape circle)
					(size 2.921 2.921)
				)
			)
		)
		(pad "1" thru_hole circle
			(at 0 -2.4511)
			(size 0.6096 0.6096)
			(drill 0.3048)
			(layers "*.Cu" "*.Mask")
			(remove_unused_layers no)
			(net "SG")
			(padstack
				(mode front_inner_back)
				(layer "Inner"
					(shape circle)
					(size 0.6096 0.6096)
					(clearance 0.1143)
				)
				(layer "B.Cu"
					(shape circle)
					(size 0.6096 0.6096)
				)
			)
		)
		(pad "2" thru_hole circle
			(at 1.733296 -1.733296)
			(size 0.6096 0.6096)
			(drill 0.3048)
			(layers "*.Cu" "*.Mask")
			(remove_unused_layers no)
			(net "SG")
			(padstack
				(mode front_inner_back)
				(layer "Inner"
					(shape circle)
					(size 0.6096 0.6096)
					(clearance 0.1143)
				)
				(layer "B.Cu"
					(shape circle)
					(size 0.6096 0.6096)
				)
			)
		)
		(pad "3" thru_hole circle
			(at 2.4511 0)
			(size 0.6096 0.6096)
			(drill 0.3048)
			(layers "*.Cu" "*.Mask")
			(remove_unused_layers no)
			(net "SG")
			(padstack
				(mode front_inner_back)
				(layer "Inner"
					(shape circle)
					(size 0.6096 0.6096)
					(clearance 0.1143)
				)
				(layer "B.Cu"
					(shape circle)
					(size 0.6096 0.6096)
				)
			)
		)
		(pad "4" thru_hole circle
			(at 1.733296 1.733296)
			(size 0.6096 0.6096)
			(drill 0.3048)
			(layers "*.Cu" "*.Mask")
			(remove_unused_layers no)
			(net "SG")
			(padstack
				(mode front_inner_back)
				(layer "Inner"
					(shape circle)
					(size 0.6096 0.6096)
					(clearance 0.1143)
				)
				(layer "B.Cu"
					(shape circle)
					(size 0.6096 0.6096)
				)
			)
		)
		(pad "5" thru_hole circle
			(at 0 2.4511)
			(size 0.6096 0.6096)
			(drill 0.3048)
			(layers "*.Cu" "*.Mask")
			(remove_unused_layers no)
			(net "SG")
			(padstack
				(mode front_inner_back)
				(layer "Inner"
					(shape circle)
					(size 0.6096 0.6096)
					(clearance 0.1143)
				)
				(layer "B.Cu"
					(shape circle)
					(size 0.6096 0.6096)
				)
			)
		)
		(pad "6" thru_hole circle
			(at -1.733296 1.733296)
			(size 0.6096 0.6096)
			(drill 0.3048)
			(layers "*.Cu" "*.Mask")
			(remove_unused_layers no)
			(net "SG")
			(padstack
				(mode front_inner_back)
				(layer "Inner"
					(shape circle)
					(size 0.6096 0.6096)
					(clearance 0.1143)
				)
				(layer "B.Cu"
					(shape circle)
					(size 0.6096 0.6096)
				)
			)
		)
		(pad "7" thru_hole circle
			(at -2.4511 0)
			(size 0.6096 0.6096)
			(drill 0.3048)
			(layers "*.Cu" "*.Mask")
			(remove_unused_layers no)
			(net "SG")
			(padstack
				(mode front_inner_back)
				(layer "Inner"
					(shape circle)
					(size 0.6096 0.6096)
					(clearance 0.1143)
				)
				(layer "B.Cu"
					(shape circle)
					(size 0.6096 0.6096)
				)
			)
		)
		(pad "8" thru_hole circle
			(at -1.733296 -1.733296)
			(size 0.6096 0.6096)
			(drill 0.3048)
			(layers "*.Cu" "*.Mask")
			(remove_unused_layers no)
			(net "SG")
			(padstack
				(mode front_inner_back)
				(layer "Inner"
					(shape circle)
					(size 0.6096 0.6096)
					(clearance 0.1143)
				)
				(layer "B.Cu"
					(shape circle)
					(size 0.6096 0.6096)
				)
			)
		)
		(zone
			(layers "F.Cu" "B.Cu" "In1.Cu" "In2.Cu" "In3.Cu" "In4.Cu" "In5.Cu" "In6.Cu"
				"In7.Cu" "In8.Cu"
			)
			(hatch none 0.5)
			(connect_pads
				(clearance 0)
			)
			(min_thickness 0.25)
			(keepout
				(tracks not_allowed)
				(vias allowed)
				(pads allowed)
				(copperpour not_allowed)
				(footprints allowed)
			)
			(placement
				(enabled no)
				(sheetname "")
			)
			(fill
				(thermal_gap 0.5)
				(thermal_bridge_width 0.5)
				(island_removal_mode 0)
			)
			(polygon
				(pts
					(arc
						(start 9.392412 -94.749874)
						(mid 5.607812 -94.749874)
						(end 9.392412 -94.749874)
					)
				)
			)
		)
	)
	(footprint ""
		(layer "F.Cu")
		(at 63.784988 -15.367 -90)
		(property "Reference" "R22"
			(at -2.413 -0.038862 90)
			(unlocked yes)
			(layer "F.SilkS")
			(effects
				(font
					(size 0.7874 0.5842)
					(thickness 0.1524)
				)
			)
		)
		(property "Value" "VAL*"
			(at 0.02032 2.13233 270)
			(unlocked yes)
			(layer "F.Fab")
			(hide yes)
			(effects
				(font
					(size 0.7874 0.5842)
					(thickness 0.1524)
				)
			)
		)
		(property "Tolerance" "TOL*"
			(at 0.044704 3.05435 270)
			(unlocked yes)
			(layer "Cmts.User")
			(hide yes)
			(effects
				(font
					(size 0.7874 0.5842)
					(thickness 0.1524)
				)
			)
		)
		(property "User Part Number" "PARTNUM*"
			(at 0.02032 4.024884 270)
			(unlocked yes)
			(layer "Cmts.User")
			(hide yes)
			(effects
				(font
					(size 0.7874 0.5842)
					(thickness 0.1524)
				)
			)
		)
		(property "Device Type" "RESISTOR-G155-100R0-J0,0OHM,-"
			(at 0.008382 1.210564 270)
			(unlocked yes)
			(layer "F.Fab")
			(hide yes)
			(effects
				(font
					(size 0.7874 0.5842)
					(thickness 0.1524)
				)
			)
		)
		(duplicate_pad_numbers_are_jumpers no)
		(fp_line
			(start -1.143 0.5588)
			(end 1.143 0.5588)
			(stroke
				(width 0.1)
				(type default)
			)
			(layer "F.SilkS")
		)
		(fp_line
			(start 1.143 0.5588)
			(end 1.143 -0.5588)
			(stroke
				(width 0.1)
				(type default)
			)
			(layer "F.SilkS")
		)
		(fp_line
			(start -1.143 -0.5588)
			(end -1.143 0.5588)
			(stroke
				(width 0.1)
				(type default)
			)
			(layer "F.SilkS")
		)
		(fp_line
			(start 1.143 -0.5588)
			(end -1.143 -0.5588)
			(stroke
				(width 0.1)
				(type default)
			)
			(layer "F.SilkS")
		)
		(fp_rect
			(start -1.143 -0.5588)
			(end 1.143 0.5588)
			(stroke
				(width 0)
				(type default)
			)
			(fill no)
			(layer "F.CrtYd")
		)
		(fp_line
			(start -0.508 0.3048)
			(end 0.508 0.3048)
			(stroke
				(width 0.1)
				(type default)
			)
			(layer "F.Fab")
		)
		(fp_line
			(start 0.508 0.3048)
			(end 0.508 -0.3048)
			(stroke
				(width 0.1)
				(type default)
			)
			(layer "F.Fab")
		)
		(fp_line
			(start -0.508 -0.3048)
			(end -0.508 0.3048)
			(stroke
				(width 0.1)
				(type default)
			)
			(layer "F.Fab")
		)
		(fp_line
			(start 0.508 -0.3048)
			(end -0.508 -0.3048)
			(stroke
				(width 0.1)
				(type default)
			)
			(layer "F.Fab")
		)
		(pad "1" smd rect
			(at -0.5334 0 270)
			(size 0.7112 0.6096)
			(layers "F.Cu" "F.Mask" "F.Paste")
			(net "CARD_PRESENT")
		)
		(pad "2" smd rect
			(at 0.5334 0 270)
			(size 0.7112 0.6096)
			(layers "F.Cu" "F.Mask" "F.Paste")
			(net "UNNAMED_3_CONN64PGF_I61_PRSNT21")
		)
		(zone
			(layer "F.Cu")
			(hatch none 0.5)
			(connect_pads
				(clearance 0)
			)
			(min_thickness 0.25)
			(keepout
				(tracks allowed)
				(vias not_allowed)
				(pads allowed)
				(copperpour not_allowed)
				(footprints allowed)
			)
			(placement
				(enabled no)
				(sheetname "")
			)
			(fill
				(thermal_gap 0.5)
				(thermal_bridge_width 0.5)
				(island_removal_mode 0)
			)
			(polygon
				(pts
					(xy 64.089788 -15.4432) (xy 63.480188 -15.4432) (xy 63.480188 -15.2908) (xy 64.089788 -15.2908)
				)
			)
		)
	)
	(footprint ""
		(layer "F.Cu")
		(at 135.5344 -94.107 90)
		(property "Reference" "C9"
			(at -2.921 0.01397 90)
			(unlocked yes)
			(layer "F.SilkS")
			(effects
				(font
					(size 0.7874 0.5842)
					(thickness 0.1524)
				)
			)
		)
		(property "Value" "VAL*"
			(at 0.0762 3.134106 90)
			(unlocked yes)
			(layer "F.Fab")
			(hide yes)
			(effects
				(font
					(size 0.7874 0.5842)
					(thickness 0.1524)
				)
			)
		)
		(property "Device Type" "CAPACITOR-G107-0F106-EM,10UF,2A"
			(at 0.0508 2.194306 90)
			(unlocked yes)
			(layer "F.Fab")
			(hide yes)
			(effects
				(font
					(size 0.7874 0.5842)
					(thickness 0.1524)
				)
			)
		)
		(property "User Part Number" "PARTNUM*"
			(at 0.1016 5.013706 90)
			(unlocked yes)
			(layer "Cmts.User")
			(hide yes)
			(effects
				(font
					(size 0.7874 0.5842)
					(thickness 0.1524)
				)
			)
		)
		(property "Tolerance" "TOL*"
			(at 0.0762 4.048506 90)
			(unlocked yes)
			(layer "Cmts.User")
			(hide yes)
			(effects
				(font
					(size 0.7874 0.5842)
					(thickness 0.1524)
				)
			)
		)
		(duplicate_pad_numbers_are_jumpers no)
		(fp_line
			(start 1.5748 -0.9398)
			(end -1.5748 -0.9398)
			(stroke
				(width 0.1)
				(type default)
			)
			(layer "F.SilkS")
		)
		(fp_line
			(start -1.5748 -0.9398)
			(end -1.5748 0.9398)
			(stroke
				(width 0.1)
				(type default)
			)
			(layer "F.SilkS")
		)
		(fp_line
			(start 1.5748 0.9398)
			(end 1.5748 -0.9398)
			(stroke
				(width 0.1)
				(type default)
			)
			(layer "F.SilkS")
		)
		(fp_line
			(start -1.5748 0.9398)
			(end 1.5748 0.9398)
			(stroke
				(width 0.1)
				(type default)
			)
			(layer "F.SilkS")
		)
		(fp_rect
			(start 1.5748 0.9398)
			(end -1.5748 -0.9398)
			(stroke
				(width 0)
				(type default)
			)
			(fill no)
			(layer "F.CrtYd")
		)
		(fp_line
			(start 1.016 -0.635)
			(end -1.016 -0.635)
			(stroke
				(width 0.1)
				(type default)
			)
			(layer "F.Fab")
		)
		(fp_line
			(start -1.016 -0.635)
			(end -1.016 0.635)
			(stroke
				(width 0.1)
				(type default)
			)
			(layer "F.Fab")
		)
		(fp_line
			(start 1.016 0.635)
			(end 1.016 -0.635)
			(stroke
				(width 0.1)
				(type default)
			)
			(layer "F.Fab")
		)
		(fp_line
			(start -1.016 0.635)
			(end 1.016 0.635)
			(stroke
				(width 0.1)
				(type default)
			)
			(layer "F.Fab")
		)
		(pad "1" smd rect
			(at -0.8382 0 90)
			(size 0.9652 1.3716)
			(layers "F.Cu" "F.Mask" "F.Paste")
			(net "XP12R0V")
		)
		(pad "2" smd rect
			(at 0.8382 0 90)
			(size 0.9652 1.3716)
			(layers "F.Cu" "F.Mask" "F.Paste")
			(net "SG")
		)
		(zone
			(layer "F.Cu")
			(hatch none 0.5)
			(connect_pads
				(clearance 0)
			)
			(min_thickness 0.25)
			(keepout
				(tracks allowed)
				(vias not_allowed)
				(pads allowed)
				(copperpour not_allowed)
				(footprints allowed)
			)
			(placement
				(enabled no)
				(sheetname "")
			)
			(fill
				(thermal_gap 0.5)
				(thermal_bridge_width 0.5)
				(island_removal_mode 0)
			)
			(polygon
				(pts
					(xy 136.1694 -94.3356) (xy 134.8994 -94.3356) (xy 134.8994 -93.8784) (xy 136.1694 -93.8784)
				)
			)
		)
	)
)
